#ISCELL
  pure_quanta quanta_title_block_c *
  *
#CELL
  pure_quanta q_led *
  page47_i10
#CELL
  pure_quanta q_led *
  page47_i11
#CELL
  pure_quanta q_led *
  page47_i12
#CELL
  pure_quanta q_led *
  page47_i13
#CELL
  pure_quanta q_led *
  page47_i14
#CELL
  pure_quanta q_res *
  page47_i18
#CELL
  pure_quanta q_res *
  page47_i20
#CELL
  pure_quanta q_res *
  page47_i23
#CELL
  pure_quanta q_res *
  page47_i25
#CELL
  pure_quanta q_res *
  page47_i31
#CELL
  pure_quanta q_res *
  page47_i33
#CELL
  pure_quanta q_res *
  page47_i35
#CELL
  pure_quanta q_res *
  page47_i37
#ISCELL
  logical_power universal_gnd *
  page47_i39
#ISCELL
  standard offpage *
  page47_i40
#ISCELL
  standard offpage *
  page47_i41
#ISCELL
  standard offpage *
  page47_i42
#ISCELL
  standard offpage *
  page47_i43
#ISCELL
  standard offpage *
  page47_i44
#ISCELL
  standard offpage *
  page47_i45
#ISCELL
  standard offpage *
  page47_i46
#ISCELL
  standard offpage *
  page47_i47
#CELL
  pure_quanta q_res *
  page47_i48
#ISCELL
  standard offpage *
  page47_i49
#CELL
  pure_quanta q_led *
  page47_i5
#CELL
  pure_quanta q_res *
  page47_i50
#ISCELL
  standard offpage *
  page47_i51
#CELL
  pure_quanta q_res *
  page47_i52
#ISCELL
  standard offpage *
  page47_i53
#CELL
  pure_quanta q_res *
  page47_i54
#ISCELL
  standard offpage *
  page47_i55
#CELL
  pure_quanta q_res *
  page47_i56
#ISCELL
  standard offpage *
  page47_i57
#CELL
  pure_quanta q_res *
  page47_i58
#ISCELL
  standard offpage *
  page47_i59
#CELL
  pure_quanta q_res *
  page47_i60
#ISCELL
  standard offpage *
  page47_i61
#CELL
  pure_quanta q_res *
  page47_i62
#ISCELL
  standard offpage *
  page47_i63
#CELL
  pure_quanta q_led *
  page47_i7
#CELL
  pure_quanta q_led *
  page47_i9
